(kicad_pcb
	(version 20241229)
	(generator "pcbnew")
	(generator_version "9.0")
	(general
		(thickness 1.61)
		(legacy_teardrops no)
	)
	(paper "A3")
	(title_block
		(title "SO-DIMM DDR5 Tester")
		(date "2025-11-26")
		(rev "1.3.0")
		(comment 9 "footprints 99-103 of 627")
	)
	(layers
		(0 "F.Cu" signal)
		(4 "In1.Cu" power)
		(6 "In2.Cu" mixed)
		(8 "In3.Cu" power)
		(10 "In4.Cu" mixed)
		(12 "In5.Cu" power)
		(14 "In6.Cu" mixed)
		(16 "In7.Cu" power)
		(18 "In8.Cu" power)
		(20 "In9.Cu" mixed)
		(22 "In10.Cu" power)
		(2 "B.Cu" signal)
		(9 "F.Adhes" user "F.Adhesive")
		(11 "B.Adhes" user "B.Adhesive")
		(13 "F.Paste" user)
		(15 "B.Paste" user)
		(5 "F.SilkS" user "F.Silkscreen")
		(7 "B.SilkS" user "B.Silkscreen")
		(1 "F.Mask" user)
		(3 "B.Mask" user)
		(17 "Dwgs.User" user "User.Drawings")
		(19 "Cmts.User" user "User.Comments")
		(21 "Eco1.User" user "User.Eco1")
		(23 "Eco2.User" user "User.Eco2")
		(25 "Edge.Cuts" user)
		(27 "Margin" user)
		(31 "F.CrtYd" user "F.Courtyard")
		(29 "B.CrtYd" user "B.Courtyard")
		(35 "F.Fab" user)
		(33 "B.Fab" user)
	)
	(footprint "antmicro-footprints:R_0402_1005Metric"
		(layer "F.Cu")
		(at 94.3 194.815 90)
		(descr "Resistor SMD 0402")
		(tags "resistor SMD 0402")
		(property "Reference" "R65"
			(at -1.122484 -0.772697 90)
			(layer "F.SilkS")
			(hide yes)
			(effects
				(font
					(size 0.7 0.7)
					(thickness 0.15)
				)
				(justify left bottom)
			)
		)
		(property "Value" "R_330R_0402"
			(at -1.011843 1.772047 90)
			(layer "F.Fab")
			(effects
				(font
					(size 0.7 0.7)
					(thickness 0.15)
				)
				(justify left bottom)
			)
		)
		(property "Datasheet" "https://www.bourns.com/docs/product-datasheets/cr.pdf"
			(at 0 0 90)
			(layer "F.Fab")
			(hide yes)
			(effects
				(font
					(size 1.27 1.27)
					(thickness 0.15)
				)
			)
		)
		(property "Author" "Antmicro"
			(at 289.115 100.515 0)
			(layer "F.Fab")
			(hide yes)
			(effects
				(font
					(size 1 1)
					(thickness 0.15)
				)
			)
		)
		(property "License" "Apache-2.0"
			(at 289.115 100.515 0)
			(layer "F.Fab")
			(hide yes)
			(effects
				(font
					(size 1 1)
					(thickness 0.15)
				)
			)
		)
		(property "MPN" "CR0402-FX-3300GLF"
			(at 289.115 100.515 0)
			(layer "F.Fab")
			(hide yes)
			(effects
				(font
					(size 1 1)
					(thickness 0.15)
				)
			)
		)
		(property "Manufacturer" "Bourns"
			(at 289.115 100.515 0)
			(layer "F.Fab")
			(hide yes)
			(effects
				(font
					(size 1 1)
					(thickness 0.15)
				)
			)
		)
		(property "Tolerance" "1%"
			(at 289.115 100.515 0)
			(layer "F.Fab")
			(hide yes)
			(effects
				(font
					(size 1 1)
					(thickness 0.15)
				)
			)
		)
		(property "Val" "330R"
			(at 289.115 100.515 0)
			(layer "F.Fab")
			(hide yes)
			(effects
				(font
					(size 1 1)
					(thickness 0.15)
				)
			)
		)
		(sheetname "/Debug FTDI/")
		(sheetfile "debug-ftdi.kicad_sch")
		(attr smd)
		(fp_rect
			(start -0.93 -0.47)
			(end 0.93 0.47)
			(stroke
				(width 0.05)
				(type solid)
			)
			(fill no)
			(layer "F.CrtYd")
		)
		(fp_rect
			(start -0.5 -0.25)
			(end 0.5 0.25)
			(stroke
				(width 0.15)
				(type solid)
			)
			(fill no)
			(layer "F.Fab")
		)
		(pad "1" smd roundrect
			(at -0.485 0 90)
			(size 0.59 0.64)
			(layers "F.Cu" "F.Mask" "F.Paste")
			(roundrect_rratio 0.25)
			(net 316 "Net-(D11-Pad1)")
			(pintype "passive")
		)
		(pad "2" smd roundrect
			(at 0.485 0 90)
			(size 0.59 0.64)
			(layers "F.Cu" "F.Mask" "F.Paste")
			(roundrect_rratio 0.25)
			(net 657 "/Debug FTDI/LED_RX0")
			(pintype "passive")
		)
	)
	(footprint "antmicro-footprints:R_0402_1005Metric"
		(layer "F.Cu")
		(at 177.9125 181.315)
		(descr "Resistor SMD 0402")
		(tags "resistor SMD 0402")
		(property "Reference" "R137"
			(at -1.122484 -0.772697 0)
			(layer "F.SilkS")
			(hide yes)
			(effects
				(font
					(size 0.7 0.7)
					(thickness 0.15)
				)
				(justify left bottom)
			)
		)
		(property "Value" "R_0R_0402"
			(at -1.011843 1.772047 0)
			(layer "F.Fab")
			(effects
				(font
					(size 0.7 0.7)
					(thickness 0.15)
				)
				(justify left bottom)
			)
		)
		(property "Datasheet" "https://industrial.panasonic.com/cdbs/www-data/pdf/RDA0000/AOA0000C301.pdf"
			(at 0 0 0)
			(layer "F.Fab")
			(hide yes)
			(effects
				(font
					(size 1.27 1.27)
					(thickness 0.15)
				)
			)
		)
		(property "Author" "Antmicro"
			(at 0 0 0)
			(layer "F.Fab")
			(hide yes)
			(effects
				(font
					(size 1 1)
					(thickness 0.15)
				)
			)
		)
		(property "Current" "1A"
			(at 0 0 0)
			(layer "F.Fab")
			(hide yes)
			(effects
				(font
					(size 1 1)
					(thickness 0.15)
				)
			)
		)
		(property "License" "Apache-2.0"
			(at 0 0 0)
			(layer "F.Fab")
			(hide yes)
			(effects
				(font
					(size 1 1)
					(thickness 0.15)
				)
			)
		)
		(property "MPN" "ERJ2GE0R00X"
			(at 0 0 0)
			(layer "F.Fab")
			(hide yes)
			(effects
				(font
					(size 1 1)
					(thickness 0.15)
				)
			)
		)
		(property "Manufacturer" "Panasonic"
			(at 0 0 0)
			(layer "F.Fab")
			(hide yes)
			(effects
				(font
					(size 1 1)
					(thickness 0.15)
				)
			)
		)
		(property "Tolerance" ""
			(at 0 0 0)
			(layer "F.Fab")
			(hide yes)
			(effects
				(font
					(size 1 1)
					(thickness 0.15)
				)
			)
		)
		(property "Val" "0R"
			(at 0 0 0)
			(layer "F.Fab")
			(hide yes)
			(effects
				(font
					(size 1 1)
					(thickness 0.15)
				)
			)
		)
		(sheetname "/Supply/")
		(sheetfile "supply.kicad_sch")
		(attr smd)
		(fp_rect
			(start -0.93 -0.47)
			(end 0.93 0.47)
			(stroke
				(width 0.05)
				(type solid)
			)
			(fill no)
			(layer "F.CrtYd")
		)
		(fp_rect
			(start -0.5 -0.25)
			(end 0.5 0.25)
			(stroke
				(width 0.15)
				(type solid)
			)
			(fill no)
			(layer "F.Fab")
		)
		(pad "1" smd roundrect
			(at -0.485 0)
			(size 0.59 0.64)
			(layers "F.Cu" "F.Mask" "F.Paste")
			(roundrect_rratio 0.25)
			(net 240 "POWER")
			(pintype "passive")
		)
		(pad "2" smd roundrect
			(at 0.485 0)
			(size 0.59 0.64)
			(layers "F.Cu" "F.Mask" "F.Paste")
			(roundrect_rratio 0.25)
			(net 281 "/Supply/PG2")
			(pintype "passive")
		)
	)
	(footprint "antmicro-footprints:TP_1206_SMD_RCW-0C"
		(layer "F.Cu")
		(at 194 177.1 180)
		(property "Reference" "TP14"
			(at -2.29 -1.4 180)
			(layer "F.SilkS")
			(hide yes)
			(effects
				(font
					(size 0.7 0.7)
					(thickness 0.15)
				)
				(justify left bottom)
			)
		)
		(property "Value" "TP_1206_SMD_RCW-0C"
			(at -4.68 2.25 180)
			(layer "F.Fab")
			(effects
				(font
					(size 0.7 0.7)
					(thickness 0.15)
				)
				(justify left bottom)
			)
		)
		(property "Datasheet" "https://www.te.com/commerce/DocumentDelivery/DDEController?Action=srchrtrv&DocNm=1773266&DocType=DS&DocLang=English"
			(at 0 0 180)
			(layer "F.Fab")
			(hide yes)
			(effects
				(font
					(size 1.27 1.27)
					(thickness 0.15)
				)
			)
		)
		(property "Author" "Antmicro"
			(at 388 354.2 0)
			(layer "F.Fab")
			(hide yes)
			(effects
				(font
					(size 1 1)
					(thickness 0.15)
				)
			)
		)
		(property "License" "Apache-2.0"
			(at 388 354.2 0)
			(layer "F.Fab")
			(hide yes)
			(effects
				(font
					(size 1 1)
					(thickness 0.15)
				)
			)
		)
		(property "MPN" "RCW-0C"
			(at 388 354.2 0)
			(layer "F.Fab")
			(hide yes)
			(effects
				(font
					(size 1 1)
					(thickness 0.15)
				)
			)
		)
		(property "Manufacturer" "TE Connectivity"
			(at 388 354.2 0)
			(layer "F.Fab")
			(hide yes)
			(effects
				(font
					(size 1 1)
					(thickness 0.15)
				)
			)
		)
		(sheetname "/Supply/")
		(sheetfile "supply.kicad_sch")
		(attr smd)
		(fp_line
			(start 1.78 0.982)
			(end 1.78 0.482)
			(stroke
				(width 0.15)
				(type solid)
			)
			(layer "F.SilkS")
		)
		(fp_line
			(start 1.78 0.982)
			(end 1.281 0.982)
			(stroke
				(width 0.15)
				(type solid)
			)
			(layer "F.SilkS")
		)
		(fp_line
			(start 1.78 -0.981)
			(end 1.78 -0.479)
			(stroke
				(width 0.15)
				(type solid)
			)
			(layer "F.SilkS")
		)
		(fp_line
			(start 1.78 -0.981)
			(end 1.281 -0.981)
			(stroke
				(width 0.15)
				(type solid)
			)
			(layer "F.SilkS")
		)
		(fp_line
			(start -1.779 0.98)
			(end -1.279 0.98)
			(stroke
				(width 0.15)
				(type solid)
			)
			(layer "F.SilkS")
		)
		(fp_line
			(start -1.779 0.482)
			(end -1.779 0.98)
			(stroke
				(width 0.15)
				(type solid)
			)
			(layer "F.SilkS")
		)
		(fp_line
			(start -1.779 -0.981)
			(end -1.279 -0.981)
			(stroke
				(width 0.15)
				(type solid)
			)
			(layer "F.SilkS")
		)
		(fp_line
			(start -1.779 -0.981)
			(end -1.779 -0.479)
			(stroke
				(width 0.15)
				(type solid)
			)
			(layer "F.SilkS")
		)
		(fp_rect
			(start -2.101 -1.314)
			(end 2.1 1.312)
			(stroke
				(width 0.05)
				(type solid)
			)
			(fill no)
			(layer "F.CrtYd")
		)
		(fp_rect
			(start -1.601 -0.814)
			(end 1.6 0.812)
			(stroke
				(width 0.15)
				(type solid)
			)
			(fill no)
			(layer "F.Fab")
		)
		(pad "1" smd rect
			(at 0 0 180)
			(size 3.4 1.8)
			(layers "F.Cu" "F.Mask" "F.Paste")
			(net 239 "/Supply/spare")
			(pinfunction "1")
			(pintype "passive")
		)
	)
	(footprint "antmicro-footprints:SC70-3"
		(layer "F.Cu")
		(at 192.65 141.7)
		(property "Reference" "Q16"
			(at 0 -1.6 0)
			(layer "F.SilkS")
			(hide yes)
			(effects
				(font
					(size 0.7 0.7)
					(thickness 0.15)
				)
				(justify left bottom)
			)
		)
		(property "Value" "BSS138PW,115"
			(at 0 2.3 0)
			(layer "F.Fab")
			(effects
				(font
					(size 0.7 0.7)
					(thickness 0.15)
				)
				(justify left bottom)
			)
		)
		(property "Datasheet" "https://assets.nexperia.com/documents/data-sheet/BSS138PW.pdf"
			(at 0 0 0)
			(layer "F.Fab")
			(hide yes)
			(effects
				(font
					(size 1.27 1.27)
					(thickness 0.15)
				)
			)
		)
		(property "Description" "Power MOSFET, N Channel, 60 V, 320 mA, 0.9 ohm, SOT-323, Surface Mount"
			(at 0 0 0)
			(layer "F.Fab")
			(hide yes)
			(effects
				(font
					(size 1.27 1.27)
					(thickness 0.15)
				)
			)
		)
		(property "Author" "Antmicro"
			(at 0 0 0)
			(layer "F.Fab")
			(hide yes)
			(effects
				(font
					(size 1 1)
					(thickness 0.15)
				)
			)
		)
		(property "License" "Apache-2.0"
			(at 0 0 0)
			(layer "F.Fab")
			(hide yes)
			(effects
				(font
					(size 1 1)
					(thickness 0.15)
				)
			)
		)
		(property "MPN" "BSS138PW,115"
			(at 0 0 0)
			(layer "F.Fab")
			(hide yes)
			(effects
				(font
					(size 1 1)
					(thickness 0.15)
				)
			)
		)
		(property "Manufacturer" "Nexperia"
			(at 0 0 0)
			(layer "F.Fab")
			(hide yes)
			(effects
				(font
					(size 1 1)
					(thickness 0.15)
				)
			)
		)
		(sheetname "/Supply/")
		(sheetfile "supply.kicad_sch")
		(attr smd)
		(fp_line
			(start -0.3 -1)
			(end 0.627 -0.999)
			(stroke
				(width 0.15)
				(type solid)
			)
			(layer "F.SilkS")
		)
		(fp_line
			(start -0.3 1)
			(end 0.627 1.001)
			(stroke
				(width 0.15)
				(type solid)
			)
			(layer "F.SilkS")
		)
		(fp_line
			(start 0.627 -0.6)
			(end 0.627 -0.999)
			(stroke
				(width 0.15)
				(type solid)
			)
			(layer "F.SilkS")
		)
		(fp_line
			(start 0.627 0.6)
			(end 0.627 1.001)
			(stroke
				(width 0.15)
				(type solid)
			)
			(layer "F.SilkS")
		)
		(fp_line
			(start -1.4 1)
			(end -1.4 -1)
			(stroke
				(width 0.05)
				(type solid)
			)
			(layer "F.CrtYd")
		)
		(fp_line
			(start -0.9 -1.3)
			(end -0.9 -1)
			(stroke
				(width 0.05)
				(type solid)
			)
			(layer "F.CrtYd")
		)
		(fp_line
			(start -0.9 -1.3)
			(end 0.9 -1.3)
			(stroke
				(width 0.05)
				(type solid)
			)
			(layer "F.CrtYd")
		)
		(fp_line
			(start -0.9 -1)
			(end -1.4 -1)
			(stroke
				(width 0.05)
				(type solid)
			)
			(layer "F.CrtYd")
		)
		(fp_line
			(start -0.9 1)
			(end -1.4 1)
			(stroke
				(width 0.05)
				(type solid)
			)
			(layer "F.CrtYd")
		)
		(fp_line
			(start -0.9 1.3)
			(end -0.9 1)
			(stroke
				(width 0.05)
				(type solid)
			)
			(layer "F.CrtYd")
		)
		(fp_line
			(start 0.9 -1.3)
			(end 0.9 -0.4)
			(stroke
				(width 0.05)
				(type solid)
			)
			(layer "F.CrtYd")
		)
		(fp_line
			(start 0.9 -0.4)
			(end 1.4 -0.4)
			(stroke
				(width 0.05)
				(type solid)
			)
			(layer "F.CrtYd")
		)
		(fp_line
			(start 0.9 0.4)
			(end 0.9 1.3)
			(stroke
				(width 0.05)
				(type solid)
			)
			(layer "F.CrtYd")
		)
		(fp_line
			(start 0.9 1.3)
			(end -0.9 1.3)
			(stroke
				(width 0.05)
				(type solid)
			)
			(layer "F.CrtYd")
		)
		(fp_line
			(start 1.4 -0.4)
			(end 1.4 0.4)
			(stroke
				(width 0.05)
				(type solid)
			)
			(layer "F.CrtYd")
		)
		(fp_line
			(start 1.4 0.4)
			(end 0.9 0.4)
			(stroke
				(width 0.05)
				(type solid)
			)
			(layer "F.CrtYd")
		)
		(fp_rect
			(start -0.623 -0.999)
			(end 0.627 1.001)
			(stroke
				(width 0.15)
				(type solid)
			)
			(fill no)
			(layer "F.Fab")
		)
		(pad "1" smd rect
			(at -1.051 -0.65 90)
			(size 0.6 0.6)
			(layers "F.Cu" "F.Mask" "F.Paste")
			(net 241 "FPGA_POWER_CYCLE")
			(pinfunction "G")
			(pintype "input")
		)
		(pad "2" smd rect
			(at -1.051 0.65 90)
			(size 0.6 0.6)
			(layers "F.Cu" "F.Mask" "F.Paste")
			(net 1 "GND")
			(pinfunction "S")
			(pintype "passive")
		)
		(pad "3" smd rect
			(at 1.05 0 90)
			(size 0.6 0.6)
			(layers "F.Cu" "F.Mask" "F.Paste")
			(net 367 "Net-(Q16-D)")
			(pinfunction "D")
			(pintype "passive")
		)
	)
	(footprint "antmicro-footprints:MPS_QFN-14_MP8869S"
		(layer "F.Cu")
		(at 172.869501 194.216501 -90)
		(property "Reference" "U27"
			(at 3.983499 2.069501 270)
			(layer "F.SilkS")
			(effects
				(font
					(size 0.7 0.7)
					(thickness 0.15)
				)
				(justify left bottom)
			)
		)
		(property "Value" "MP8869S"
			(at -5.5 3.43 270)
			(layer "F.Fab")
			(effects
				(font
					(size 0.7 0.7)
					(thickness 0.15)
				)
				(justify left bottom)
			)
		)
		(property "Datasheet" "https://www.mouser.com/datasheet/2/277/MP8869S-2946178.pdf"
			(at 0 0 270)
			(layer "F.Fab")
			(hide yes)
			(effects
				(font
					(size 1.27 1.27)
					(thickness 0.15)
				)
			)
		)
		(property "Author" "Antmicro"
			(at -21.347 367.086002 0)
			(layer "F.Fab")
			(hide yes)
			(effects
				(font
					(size 1 1)
					(thickness 0.15)
				)
			)
		)
		(property "License" "Apache-2.0"
			(at -21.347 367.086002 0)
			(layer "F.Fab")
			(hide yes)
			(effects
				(font
					(size 1 1)
					(thickness 0.15)
				)
			)
		)
		(property "MPN" "MP8869SGL-P"
			(at -21.347 367.086002 0)
			(layer "F.Fab")
			(hide yes)
			(effects
				(font
					(size 1 1)
					(thickness 0.15)
				)
			)
		)
		(property "Manufacturer" "Monolithic Power Systems"
			(at -21.347 367.086002 0)
			(layer "F.Fab")
			(hide yes)
			(effects
				(font
					(size 1 1)
					(thickness 0.15)
				)
			)
		)
		(property ki_fp_filters "QFN-14_MP8869S_MNP")
		(sheetname "/Supply/")
		(sheetfile "supply.kicad_sch")
		(attr smd)
		(fp_line
			(start -1.678 2.171)
			(end -1.678 0.481)
			(stroke
				(width 0.15)
				(type solid)
			)
			(layer "F.SilkS")
		)
		(fp_line
			(start 1.675 0.981)
			(end 1.675 2.171)
			(stroke
				(width 0.15)
				(type solid)
			)
			(layer "F.SilkS")
		)
		(fp_line
			(start -1.678 -0.959)
			(end -1.678 -2.173)
			(stroke
				(width 0.15)
				(type solid)
			)
			(layer "F.SilkS")
		)
		(fp_line
			(start 1.675 -2.173)
			(end 1.675 -0.983)
			(stroke
				(width 0.15)
				(type solid)
			)
			(layer "F.SilkS")
		)
		(fp_circle
			(center -2.361 -0.5)
			(end -2.311 -0.5)
			(stroke
				(width 0.15)
				(type solid)
			)
			(fill yes)
			(layer "F.SilkS")
		)
		(fp_rect
			(start -2.061 -2.55)
			(end 2.06 2.548)
			(stroke
				(width 0.05)
				(type solid)
			)
			(fill no)
			(layer "F.CrtYd")
		)
		(fp_line
			(start -1.551 2.043)
			(end 1.548 2.043)
			(stroke
				(width 0.15)
				(type solid)
			)
			(layer "F.Fab")
		)
		(fp_line
			(start 1.548 2.043)
			(end 1.548 -2.045)
			(stroke
				(width 0.15)
				(type solid)
			)
			(layer "F.Fab")
		)
		(fp_line
			(start -1.541 -1.841)
			(end -1.341 -2.04)
			(stroke
				(width 0.15)
				(type solid)
			)
			(layer "F.Fab")
		)
		(fp_line
			(start -1.551 -2.045)
			(end -1.551 2.043)
			(stroke
				(width 0.15)
				(type solid)
			)
			(layer "F.Fab")
		)
		(fp_line
			(start 1.548 -2.045)
			(end -1.551 -2.045)
			(stroke
				(width 0.15)
				(type solid)
			)
			(layer "F.Fab")
		)
		(pad "1" smd custom
			(at -1.401 -0.5 270)
			(size 0.799998 0.249998)
			(layers "F.Cu" "F.Mask" "F.Paste")
			(net 67 "/Supply/1V0_BS")
			(pinfunction "BST")
			(pintype "unspecified")
			(options
				(clearance outline)
				(anchor rect)
			)
			(primitives
				(gr_poly
					(pts
						(xy -0.400002 -0.125001) (xy -0.400002 0.124999) (xy 0.499998 0.124999) (xy 0.499998 -0.000001)
						(xy 0.374998 -0.125001)
					)
					(width 0.1)
					(fill yes)
				)
			)
		)
		(pad "2" smd rect
			(at -0.851 0 270)
			(size 1.9 0.3)
			(layers "F.Cu" "F.Mask" "F.Paste")
			(net 66 "/Supply/1V0_SW")
			(pinfunction "SW")
			(pintype "output")
		)
		(pad "3" smd rect
			(at -1.002 1.848)
			(size 0.9 0.25)
			(layers "F.Cu" "F.Mask" "F.Paste")
			(net 691 "/I^{2}C/PWR.SCL")
			(pinfunction "SCL")
			(pintype "unspecified")
		)
		(pad "4" smd rect
			(at -0.5 1.848)
			(size 0.9 0.25)
			(layers "F.Cu" "F.Mask" "F.Paste")
			(net 690 "/I^{2}C/PWR.SDA")
			(pinfunction "SDA")
			(pintype "unspecified")
		)
		(pad "5" smd rect
			(at 0 1.848)
			(size 0.9 0.25)
			(layers "F.Cu" "F.Mask" "F.Paste")
			(net 221 "/Supply/EN1")
			(pinfunction "EN")
			(pintype "unspecified")
		)
		(pad "6" smd rect
			(at 0.498 1.848)
			(size 0.9 0.25)
			(layers "F.Cu" "F.Mask" "F.Paste")
			(net 1 "GND")
			(pinfunction "A0")
			(pintype "unspecified")
		)
		(pad "7" smd rect
			(at 0.999 1.848)
			(size 0.9 0.25)
			(layers "F.Cu" "F.Mask" "F.Paste")
			(net 280 "/Supply/PG1")
			(pinfunction "PG")
			(pintype "unspecified")
		)
		(pad "8" smd custom
			(at 0.849 0.498 270)
			(size 0.127 0.127)
			(layers "F.Cu" "F.Mask" "F.Paste")
			(net 1 "GND")
			(pinfunction "PGND")
			(pintype "power_in")
			(options
				(clearance outline)
				(anchor rect)
			)
			(primitives
				(gr_poly
					(pts
						(xy 0.95 0.15) (xy 0.95 -0.15) (xy -0.55 -0.15) (xy -0.65 -0.05) (xy -0.95 -0.05) (xy -0.95 0.15)
					)
					(width 0.1)
					(fill yes)
				)
			)
		)
		(pad "9" smd custom
			(at 0.849 -0.5 270)
			(size 0.127 0.127)
			(layers "F.Cu" "F.Mask" "F.Paste")
			(net 38 "VDC")
			(pinfunction "VIN")
			(pintype "power_in")
			(options
				(clearance outline)
				(anchor rect)
			)
			(primitives
				(gr_poly
					(pts
						(xy 0.95 -0.15) (xy 0.95 0.15) (xy -0.55 0.15) (xy -0.65 0.05) (xy -0.95 0.05) (xy -0.95 -0.15)
					)
					(width 0.1)
					(fill yes)
				)
			)
		)
		(pad "10" smd rect
			(at 0.999 -1.851)
			(size 0.9 0.25)
			(layers "F.Cu" "F.Mask" "F.Paste")
			(net 78 "/Supply/1V0_REG")
			(pinfunction "VOUT")
			(pintype "unspecified")
		)
		(pad "11" smd rect
			(at 0.498 -1.851)
			(size 0.9 0.25)
			(layers "F.Cu" "F.Mask" "F.Paste")
			(net 225 "/Supply/1V0_FB")
			(pinfunction "FB")
			(pintype "unspecified")
		)
		(pad "12" smd rect
			(at 0 -1.851)
			(size 0.9 0.25)
			(layers "F.Cu" "F.Mask" "F.Paste")
			(net 75 "/Supply/1V0_SS")
			(pinfunction "SS")
			(pintype "unspecified")
		)
		(pad "13" smd rect
			(at -0.5 -1.851)
			(size 0.9 0.25)
			(layers "F.Cu" "F.Mask" "F.Paste")
			(net 63 "/Supply/1V0_VCC")
			(pinfunction "VCC")
			(pintype "power_out")
		)
		(pad "14" smd rect
			(at -1.002 -1.851)
			(size 0.9 0.25)
			(layers "F.Cu" "F.Mask" "F.Paste")
			(net 1 "GND")
			(pinfunction "AGND")
			(pintype "power_in")
		)
	)
)
